FILE_TYPE = CONNECTIVITY;
{Allegro Design Entry HDL 16.6-p007 (v16-6-112F) 10/10/2012}
"PAGE_NUMBER" = 37;
0"NC";
1"PVCCIN_CPU0\g";
2"PVCCIN_CPU0\g";
3"PVCCIN_CPU0\g";
4"PVCCIN_CPU0\g";
5"GND\g";
6"PVCCIN_CPU0\g";
7"PVCCIO_CPU0\g";
8"VSENSE_VCCINR2PMAX_CPU0";
9"VSENSE_PMAX_CPU0";
10"VSENSE_PVCCIN_CPU0_SKT_VRTN";
11"VSENSE_PVCCIN_CPU0_SKT_VSEN";
%"PVCCIN_CPU0"
"1","(-7125,4350)","0","mstr_symbols","I295";
;
HDL_POWER"PVCCIN_CPU0"
CDS_LIB"mstr_symbols"
VOLTAGE"2.0V"
BODY_TYPE"PLUMBING";
"G\NAC"1;
%"PVCCIN_CPU0"
"1","(-5250,4275)","0","mstr_symbols","I296";
;
HDL_POWER"PVCCIN_CPU0"
BODY_TYPE"PLUMBING"
CDS_LIB"mstr_symbols"
VOLTAGE"2.0V";
"G\NAC"2;
%"PVCCIN_CPU0"
"1","(-3375,4350)","0","mstr_symbols","I300";
;
HDL_POWER"PVCCIN_CPU0"
CDS_LIB"mstr_symbols"
BODY_TYPE"PLUMBING"
VOLTAGE"2.0V";
"G\NAC"3;
%"PVCCIN_CPU0"
"1","(-1500,4325)","0","mstr_symbols","I301";
;
HDL_POWER"PVCCIN_CPU0"
CDS_LIB"mstr_symbols"
VOLTAGE"2.0V"
BODY_TYPE"PLUMBING";
"G\NAC"4;
%"GND"
"1","(-375,525)","0","mstr_symbols","I302";
;
CDS_LIB"mstr_symbols"
HDL_POWER"GND"
SIZE"1B"
VOLTAGE"0.0V"
BODY_TYPE"PLUMBING";
"A\NAC"5;
%"RES"
"2","(-375,750)","0","mstr_discrete","I303";
;
CDS_SEC"1"
BOM_COST"PROC_SOCKET"
SEC_TYPE"0402"
SEC"1"
ROOM"CPU0"
CDS_LOCATION"R5D5"
CDS_LIB"mstr_discrete"
LOCATION"R5D5"
PART_NUMBER"G85996-031"
VALUE"249"
TOLERANCE"0.1%"
PACK_TYPE"0402"
MATERIAL"CHIP"
WATTAGE"1/16W";
"A"
$PN"1"9;
"B"
$PN"2"5;
%"PVCCIN_CPU0"
"1","(-775,1625)","0","mstr_symbols","I305";
;
VOLTAGE"2.0V"
CDS_LIB"mstr_symbols"
BODY_TYPE"PLUMBING"
HDL_POWER"PVCCIN_CPU0";
"G\NAC"6;
%"RES"
"2","(-775,1350)","0","mstr_discrete","I309";
;
CDS_SEC"1"
SEC_TYPE"0603"
SEC"1"
BOM_COST"PROC_SOCKET"
ROOM"CPU0"
CDS_LOCATION"R5P1"
CDS_LIB"mstr_discrete"
PART_NUMBER"G22026-050"
TOLERANCE"1%"
PACK_TYPE"0603"
VALUE"100.0K"
LOCATION"R5P1"
MATERIAL"CHIP"
WATTAGE"1/10W";
"A"
$PN"1"6;
"B"
$PN"2"8;
%"SKX_EXT_B"
"18","(-6200,2475)","0","chpset_lib","I310";
;
CDS_SEC"18"
SEC_TYPE"BGA1"
SEC"18"
CDS_LOCATION"U5D1"
ROOM"CPU0"
PACK_TYPE"BGA1"
CDS_LIB"chpset_lib"
LOCATION"U5D1"
MATERIAL"IC"
PART_NUMBER"TBD";
"VCCIN<130>"
$PN"BN78"2;
"VCCIN<131>"
$PN"BN76"2;
"VCCIN<132>"
$PN"BN74"2;
"VCCIN<133>"
$PN"BN72"2;
"VCCIN<134>"
$PN"BN70"2;
"VCCIN<135>"
$PN"BN68"2;
"VCCIN<136>"
$PN"BN66"2;
"VCCIN<137>"
$PN"BN64"2;
"VCCIN<138>"
$PN"BN62"2;
"VCCIN<139>"
$PN"BN60"2;
"VCCIN<140>"
$PN"BM83"2;
"VCCIN<141>"
$PN"BM81"2;
"VCCIN<142>"
$PN"BM79"2;
"VCCIN<143>"
$PN"BM77"2;
"VCCIN<144>"
$PN"BM75"2;
"VCCIN<145>"
$PN"BM73"2;
"VCCIN<146>"
$PN"BM71"2;
"VCCIN<147>"
$PN"BM69"2;
"VCCIN<148>"
$PN"BM67"2;
"VCCIN<149>"
$PN"BM65"2;
"VCCIN<150>"
$PN"BM63"2;
"VCCIN<151>"
$PN"BM61"2;
"VCCIN<152>"
$PN"BL84"2;
"VCCIN<153>"
$PN"BL62"2;
"VCCIN<154>"
$PN"BL60"2;
"VCCIN<155>"
$PN"BK83"2;
"VCCIN<156>"
$PN"BK81"2;
"VCCIN<157>"
$PN"BK79"2;
"VCCIN<158>"
$PN"BK77"2;
"VCCIN<159>"
$PN"BK75"2;
"VCCIN<160>"
$PN"BK73"2;
"VCCIN<161>"
$PN"BK71"2;
"VCCIN<162>"
$PN"BK69"2;
"VCCIN<163>"
$PN"BK67"2;
"VCCIN<164>"
$PN"BK65"2;
"VCCIN<165>"
$PN"BK63"2;
"VCCIN<166>"
$PN"BK61"2;
"VCCIN<167>"
$PN"BJ84"2;
"VCCIN<168>"
$PN"BJ82"2;
"VCCIN<169>"
$PN"BJ80"2;
"VCCIN<170>"
$PN"BJ78"2;
"VCCIN<171>"
$PN"BJ76"2;
"VCCIN<172>"
$PN"BJ74"2;
"VCCIN<173>"
$PN"BJ72"2;
"VCCIN<174>"
$PN"BJ70"2;
"VCCIN<175>"
$PN"BJ68"2;
"VCCIN<176>"
$PN"BJ66"2;
"VCCIN<177>"
$PN"BJ64"2;
"VCCIN<178>"
$PN"BJ62"2;
"VCCIN<179>"
$PN"BJ60"2;
"VCCIN<180>"
$PN"BH83"2;
"VCCIN<181>"
$PN"BH81"2;
"VCCIN<182>"
$PN"BH79"2;
"VCCIN<183>"
$PN"BH77"2;
"VCCIN<184>"
$PN"BH75"2;
"VCCIN<185>"
$PN"BH73"2;
"VCCIN<186>"
$PN"BH71"2;
"VCCIN<187>"
$PN"BH69"2;
"VCCIN<188>"
$PN"BH67"2;
"VCCIN<189>"
$PN"BH65"2;
"VCCIN<190>"
$PN"BH63"2;
"VCCIN<191>"
$PN"BH61"2;
"VCCIN<192>"
$PN"BG84"2;
"VCCIN<193>"
$PN"BG70"2;
"VCCIN<194>"
$PN"BG68"2;
"VCCIN<195>"
$PN"BG66"2;
"VCCIN<196>"
$PN"BG64"2;
"VCCIN<197>"
$PN"BG62"2;
"VCCIN<198>"
$PN"BG60"2;
"VCCIN<199>"
$PN"BF85"1;
"VCCIN<200>"
$PN"BF83"1;
"VCCIN<201>"
$PN"BF81"1;
"VCCIN<202>"
$PN"BF79"1;
"VCCIN<203>"
$PN"BF77"1;
"VCCIN<204>"
$PN"BF75"1;
"VCCIN<205>"
$PN"BF73"1;
"VCCIN<206>"
$PN"BF61"1;
"VCCIN<207>"
$PN"BE84"1;
"VCCIN<208>"
$PN"BE82"1;
"VCCIN<209>"
$PN"BE80"1;
"VCCIN<210>"
$PN"BE78"1;
"VCCIN<211>"
$PN"BE76"1;
"VCCIN<212>"
$PN"BE74"1;
"VCCIN<213>"
$PN"BE72"1;
"VCCIN<214>"
$PN"BE62"1;
"VCCIN<215>"
$PN"BE60"1;
"VCCIN<216>"
$PN"BD85"1;
"VCCIN<217>"
$PN"BD83"1;
"VCCIN<218>"
$PN"BD81"1;
"VCCIN<219>"
$PN"BD79"1;
"VCCIN<220>"
$PN"BD77"1;
"VCCIN<221>"
$PN"BD75"1;
"VCCIN<222>"
$PN"BD73"1;
"VCCIN<223>"
$PN"BD61"1;
"VCCIN<224>"
$PN"BC84"1;
"VCCIN<225>"
$PN"BC62"1;
"VCCIN<226>"
$PN"BC60"1;
"VCCIN<227>"
$PN"BB85"1;
"VCCIN<228>"
$PN"BB61"1;
"VCCIN<229>"
$PN"BA60"1;
"VCCIN<230>"
$PN"AY61"1;
"VCCIN<231>"
$PN"AW60"1;
"VCCIN<232>"
$PN"AV61"1;
"VCCIN<233>"
$PN"AV59"1;
"VCCIN<234>"
$PN"AU60"1;
"VCCIN<235>"
$PN"AU58"1;
"VCCIN<236>"
$PN"AT59"1;
"VCCIN<237>"
$PN"AT57"1;
"VCCIN<238>"
$PN"AR58"1;
"VCCIN<239>"
$PN"AR56"1;
"VCCIN<240>"
$PN"AP57"1;
"VCCIN<241>"
$PN"AP55"1;
"VCCIN<242>"
$PN"AN56"1;
"VCCIN<243>"
$PN"AN54"1;
"VCCIN<244>"
$PN"AN32"1;
"VCCIN<245>"
$PN"AM55"1;
"VCCIN<246>"
$PN"AM53"1;
"VCCIN<247>"
$PN"AM33"1;
"VCCIN<248>"
$PN"AL54"1;
"VCCIN<249>"
$PN"AL52"1;
"VCCIN<250>"
$PN"AL50"1;
"VCCIN<251>"
$PN"AL48"1;
"VCCIN<252>"
$PN"AL46"1;
"VCCIN<253>"
$PN"AL34"1;
"VCCIN<254>"
$PN"AK53"1;
"VCCIN<255>"
$PN"AK51"1;
"VCCIN<256>"
$PN"AK49"1;
"VCCIN<257>"
$PN"AK47"1;
"VCCIN<258>"
$PN"AK45"1;
"VCCIN<259>"
$PN"AK35"1;
"VCCIN<260>"
$PN"AJ36"1;
"VCCIN<261>"
$PN"AH41"1;
"VCCIN<262>"
$PN"AH39"1;
"VCCIN<263>"
$PN"AH37"1;
"VCCIN<264>"
$PN"AG42"1;
"VCCIN<265>"
$PN"AG40"1;
"VCCIN<266>"
$PN"AG38"1;
"VCCIN<267>"
$PN"AF43"1;
%"SKX_EXT_B"
"19","(-2425,2475)","0","chpset_lib","I311";
;
CDS_SEC"19"
PACK_TYPE"BGA1"
SEC_TYPE"BGA1"
SEC"19"
CDS_LOCATION"U5D1"
ROOM"CPU0"
CDS_LIB"chpset_lib"
LOCATION"U5D1"
MATERIAL"IC"
PART_NUMBER"TBD";
"VSS_VCCIN_SENSE"
$PN"AY85"10;
"VSENSEPMAX"
$PN"AD41"9;
"VCCIN_SENSE"
$PN"BA86"11;
"VCCINPMAX<0>"
$PN"AW86"8;
"VCCINPMAX<1>"
$PN"AV85"8;
"VCCIN<0>"
$PN"CY49"4;
"VCCIN<1>"
$PN"CY47"4;
"VCCIN<2>"
$PN"CW50"4;
"VCCIN<3>"
$PN"CW48"4;
"VCCIN<4>"
$PN"CW46"4;
"VCCIN<5>"
$PN"CV51"4;
"VCCIN<6>"
$PN"CU54"4;
"VCCIN<7>"
$PN"CU52"4;
"VCCIN<8>"
$PN"CU42"4;
"VCCIN<9>"
$PN"CU40"4;
"VCCIN<10>"
$PN"CU38"4;
"VCCIN<11>"
$PN"CT55"4;
"VCCIN<12>"
$PN"CT53"4;
"VCCIN<13>"
$PN"CT41"4;
"VCCIN<14>"
$PN"CT39"4;
"VCCIN<15>"
$PN"CT37"4;
"VCCIN<16>"
$PN"CR56"4;
"VCCIN<17>"
$PN"CR54"4;
"VCCIN<18>"
$PN"CR34"4;
"VCCIN<19>"
$PN"CP57"4;
"VCCIN<20>"
$PN"CP55"4;
"VCCIN<21>"
$PN"CP33"4;
"VCCIN<22>"
$PN"CN58"4;
"VCCIN<23>"
$PN"CN56"4;
"VCCIN<24>"
$PN"CM59"4;
"VCCIN<25>"
$PN"CM57"4;
"VCCIN<26>"
$PN"CL60"4;
"VCCIN<27>"
$PN"CL58"4;
"VCCIN<28>"
$PN"CK61"4;
"VCCIN<29>"
$PN"CK59"4;
"VCCIN<30>"
$PN"CJ60"4;
"VCCIN<31>"
$PN"CH85"4;
"VCCIN<32>"
$PN"CH61"4;
"VCCIN<33>"
$PN"CG84"4;
"VCCIN<34>"
$PN"CG60"4;
"VCCIN<35>"
$PN"CF85"4;
"VCCIN<36>"
$PN"CF61"4;
"VCCIN<37>"
$PN"CE84"4;
"VCCIN<38>"
$PN"CE60"4;
"VCCIN<39>"
$PN"CD85"4;
"VCCIN<40>"
$PN"CD83"4;
"VCCIN<41>"
$PN"CD61"4;
"VCCIN<42>"
$PN"CC84"4;
"VCCIN<43>"
$PN"CC62"4;
"VCCIN<44>"
$PN"CC60"4;
"VCCIN<45>"
$PN"CB83"4;
"VCCIN<46>"
$PN"CB81"4;
"VCCIN<47>"
$PN"CB79"4;
"VCCIN<48>"
$PN"CB77"4;
"VCCIN<49>"
$PN"CB75"4;
"VCCIN<50>"
$PN"CB73"4;
"VCCIN<51>"
$PN"CB61"4;
"VCCIN<52>"
$PN"CA84"4;
"VCCIN<53>"
$PN"CA82"4;
"VCCIN<54>"
$PN"CA80"4;
"VCCIN<55>"
$PN"CA78"4;
"VCCIN<56>"
$PN"CA76"4;
"VCCIN<57>"
$PN"CA74"4;
"VCCIN<58>"
$PN"CA72"4;
"VCCIN<59>"
$PN"CA62"4;
"VCCIN<60>"
$PN"CA60"4;
"VCCIN<61>"
$PN"BY83"3;
"VCCIN<62>"
$PN"BY81"3;
"VCCIN<63>"
$PN"BY79"3;
"VCCIN<64>"
$PN"BY77"3;
"VCCIN<65>"
$PN"BY75"3;
"VCCIN<66>"
$PN"BY73"3;
"VCCIN<67>"
$PN"BY61"3;
"VCCIN<68>"
$PN"BW84"3;
"VCCIN<69>"
$PN"BW70"3;
"VCCIN<70>"
$PN"BW68"3;
"VCCIN<71>"
$PN"BW66"3;
"VCCIN<72>"
$PN"BW64"3;
"VCCIN<73>"
$PN"BW62"3;
"VCCIN<74>"
$PN"BW60"3;
"VCCIN<75>"
$PN"BV83"3;
"VCCIN<76>"
$PN"BV81"3;
"VCCIN<77>"
$PN"BV79"3;
"VCCIN<78>"
$PN"BV77"3;
"VCCIN<79>"
$PN"BV75"3;
"VCCIN<80>"
$PN"BV73"3;
"VCCIN<81>"
$PN"BV71"3;
"VCCIN<82>"
$PN"BV69"3;
"VCCIN<83>"
$PN"BV67"3;
"VCCIN<84>"
$PN"BV65"3;
"VCCIN<85>"
$PN"BV63"3;
"VCCIN<86>"
$PN"BV61"3;
"VCCIN<87>"
$PN"BU84"3;
"VCCIN<88>"
$PN"BU82"3;
"VCCIN<89>"
$PN"BU80"3;
"VCCIN<90>"
$PN"BU78"3;
"VCCIN<91>"
$PN"BU76"3;
"VCCIN<92>"
$PN"BU74"3;
"VCCIN<93>"
$PN"BU72"3;
"VCCIN<94>"
$PN"BU70"3;
"VCCIN<95>"
$PN"BU68"3;
"VCCIN<96>"
$PN"BU66"3;
"VCCIN<97>"
$PN"BU64"3;
"VCCIN<98>"
$PN"BU62"3;
"VCCIN<99>"
$PN"BU60"3;
"VCCIN<100>"
$PN"BT83"3;
"VCCIN<101>"
$PN"BT81"3;
"VCCIN<102>"
$PN"BT79"3;
"VCCIN<103>"
$PN"BT77"3;
"VCCIN<104>"
$PN"BT75"3;
"VCCIN<105>"
$PN"BT73"3;
"VCCIN<106>"
$PN"BT71"3;
"VCCIN<107>"
$PN"BT69"3;
"VCCIN<108>"
$PN"BT67"3;
"VCCIN<109>"
$PN"BT65"3;
"VCCIN<110>"
$PN"BT63"3;
"VCCIN<111>"
$PN"BT61"3;
"VCCIN<112>"
$PN"BR84"3;
"VCCIN<113>"
$PN"BR62"3;
"VCCIN<114>"
$PN"BR60"3;
"VCCIN<115>"
$PN"BP83"3;
"VCCIN<116>"
$PN"BP81"3;
"VCCIN<117>"
$PN"BP79"3;
"VCCIN<118>"
$PN"BP77"3;
"VCCIN<119>"
$PN"BP75"3;
"VCCIN<120>"
$PN"BP73"3;
"VCCIN<121>"
$PN"BP71"3;
"VCCIN<122>"
$PN"BP69"3;
"VCCIN<123>"
$PN"BP67"3;
"VCCIN<124>"
$PN"BP65"3;
"VCCIN<125>"
$PN"BP63"3;
"VCCIN<126>"
$PN"BP61"3;
"VCCIN<127>"
$PN"BN84"3;
"VCCIN<128>"
$PN"BN82"3;
"VCCIN<129>"
$PN"BN80"3;
%"RES"
"2","(-375,1125)","0","mstr_discrete","I312";
;
CDS_SEC"1"
CDS_LOCATION"R5D6"
SEC_TYPE"0402"
SEC"1"
ROOM"CPU0"
CDS_LIB"mstr_discrete"
MATERIAL"EMPTY"
LOCATION"R5D6"
VALUE"10.0"
WATTAGE"1/16W"
TOLERANCE"1%"
PART_NUMBER"G21796-066"
PACK_TYPE"0402";
"A"
$PN"1"7;
"B"
$PN"2"9;
%"PVCCIO_CPU0"
"1","(-375,1450)","0","mstr_symbols","I313";
;
HDL_POWER"PVCCIO_CPU0"
VOLTAGE"1.1V"
CDS_LIB"mstr_symbols"
BODY_TYPE"PLUMBING";
"G\NAC"7;
END.
